(kicad_pcb
	(version 20241229)
	(generator "pcbnew")
	(generator_version "9.0")
	(general
		(thickness 1.6296)
		(legacy_teardrops no)
	)
	(paper "A3")
	(title_block
		(title "Thunderbolt to 10GbE adapter")
		(date "2026-04-21")
		(rev "1.1.0")
		(company "Antmicro Ltd")
		(comment 1 "www.antmicro.com")
		(comment 9 "footprints 101-105 of 703")
	)
	(layers
		(0 "F.Cu" signal)
		(4 "In1.Cu" signal)
		(6 "In2.Cu" signal)
		(8 "In3.Cu" signal)
		(10 "In4.Cu" signal)
		(12 "In5.Cu" signal)
		(14 "In6.Cu" signal)
		(2 "B.Cu" signal)
		(9 "F.Adhes" user "F.Adhesive")
		(11 "B.Adhes" user "B.Adhesive")
		(13 "F.Paste" user)
		(15 "B.Paste" user)
		(5 "F.SilkS" user "F.Silkscreen")
		(7 "B.SilkS" user "B.Silkscreen")
		(1 "F.Mask" user)
		(3 "B.Mask" user)
		(17 "Dwgs.User" user "User.Drawings")
		(19 "Cmts.User" user "User.Comments")
		(21 "Eco1.User" user "User.Eco1")
		(23 "Eco2.User" user "User.Eco2")
		(25 "Edge.Cuts" user)
		(27 "Margin" user)
		(31 "F.CrtYd" user "F.Courtyard")
		(29 "B.CrtYd" user "B.Courtyard")
		(35 "F.Fab" user)
		(33 "B.Fab" user)
	)
	(footprint "antmicro-footprints:R_0402_1005Metric"
		(layer "F.Cu")
		(at 143.849998 108.15 180)
		(descr "Resistor SMD 0402")
		(tags "resistor SMD 0402")
		(property "Reference" "R91"
			(at -15.349999 -17.25 180)
			(layer "F.SilkS")
			(effects
				(font
					(size 0.7 0.7)
					(thickness 0.15)
				)
			)
		)
		(property "Value" "R_100k_0402"
			(at -1.011843 1.772047 180)
			(layer "F.Fab")
			(effects
				(font
					(size 0.7 0.7)
					(thickness 0.15)
				)
				(justify left bottom)
			)
		)
		(property "Datasheet" "https://www.bourns.com/docs/product-datasheets/cr.pdf"
			(at 0 0 180)
			(layer "F.Fab")
			(hide yes)
			(effects
				(font
					(size 1.27 1.27)
					(thickness 0.15)
				)
			)
		)
		(property "Description" "SMD Chip Resistor, 100 kohm, ± 1%, 62.5 mW, 0402 [1005 Metric], Thick Film, General Purpose"
			(at 0 0 180)
			(layer "F.Fab")
			(hide yes)
			(effects
				(font
					(size 1.27 1.27)
					(thickness 0.15)
				)
			)
		)
		(property "MPN" "CR0402-FX-1003GLF"
			(at 0 0 180)
			(unlocked yes)
			(layer "F.Fab")
			(hide yes)
			(effects
				(font
					(size 1 1)
					(thickness 0.15)
				)
			)
		)
		(property "Manufacturer" "Bourns"
			(at 0 0 180)
			(unlocked yes)
			(layer "F.Fab")
			(hide yes)
			(effects
				(font
					(size 1 1)
					(thickness 0.15)
				)
			)
		)
		(property "License" "Apache-2.0"
			(at 0 0 180)
			(unlocked yes)
			(layer "F.Fab")
			(hide yes)
			(effects
				(font
					(size 1 1)
					(thickness 0.15)
				)
			)
		)
		(property "Author" "Antmicro"
			(at 0 0 180)
			(unlocked yes)
			(layer "F.Fab")
			(hide yes)
			(effects
				(font
					(size 1 1)
					(thickness 0.15)
				)
			)
		)
		(property "Val" "100k"
			(at 0 0 180)
			(unlocked yes)
			(layer "F.Fab")
			(hide yes)
			(effects
				(font
					(size 1 1)
					(thickness 0.15)
				)
			)
		)
		(property "Tolerance" "1%"
			(at 0 0 180)
			(unlocked yes)
			(layer "F.Fab")
			(hide yes)
			(effects
				(font
					(size 1 1)
					(thickness 0.15)
				)
			)
		)
		(sheetname "/X710 DCDC converters/")
		(sheetfile "DCDC_converters_X710.kicad_sch")
		(attr smd)
		(fp_rect
			(start -0.925 -0.47)
			(end 0.925 0.47)
			(stroke
				(width 0.05)
				(type default)
			)
			(fill no)
			(layer "F.CrtYd")
		)
		(fp_rect
			(start -0.5 -0.25)
			(end 0.5 0.25)
			(stroke
				(width 0.15)
				(type solid)
			)
			(fill no)
			(layer "F.Fab")
		)
		(fp_text user "License: Apache-2.0"
			(at -0.95 5.169 180)
			(layer "F.Fab")
			(effects
				(font
					(size 0.7 0.7)
					(thickness 0.15)
				)
				(justify left bottom)
			)
		)
		(fp_text user "Author: Antmicro"
			(at -0.95 4.169 180)
			(layer "F.Fab")
			(effects
				(font
					(size 0.7 0.7)
					(thickness 0.15)
				)
				(justify left bottom)
			)
		)
		(fp_text user "${REFERENCE}"
			(at -0.95 3.168 180)
			(layer "F.Fab")
			(effects
				(font
					(size 0.7 0.7)
					(thickness 0.15)
				)
				(justify left bottom)
			)
		)
		(pad "1" smd roundrect
			(at -0.48 0 180)
			(size 0.59 0.64)
			(layers "F.Cu" "F.Mask" "F.Paste")
			(roundrect_rratio 0.25)
			(net 355 "/X710 DCDC converters/DVDD_PG")
			(pintype "passive")
		)
		(pad "2" smd roundrect
			(at 0.48 0 180)
			(size 0.59 0.64)
			(layers "F.Cu" "F.Mask" "F.Paste")
			(roundrect_rratio 0.25)
			(net 116 "/X710 DCDC converters/DVDD_VCC")
			(pintype "passive")
		)
	)
	(footprint "antmicro-footprints:R_0402_1005Metric"
		(layer "F.Cu")
		(at 130.509997 116.5 -90)
		(descr "Resistor SMD 0402")
		(tags "resistor SMD 0402")
		(property "Reference" "R67"
			(at -0.9 -0.290003 270)
			(layer "F.SilkS")
			(effects
				(font
					(size 0.7 0.7)
					(thickness 0.15)
				)
				(justify left bottom)
			)
		)
		(property "Value" "R_10k_0402"
			(at -1.011843 1.772047 270)
			(layer "F.Fab")
			(effects
				(font
					(size 0.7 0.7)
					(thickness 0.15)
				)
				(justify left bottom)
			)
		)
		(property "Datasheet" "https://www.bourns.com/docs/product-datasheets/cr.pdf"
			(at 0 0 270)
			(layer "F.Fab")
			(hide yes)
			(effects
				(font
					(size 1.27 1.27)
					(thickness 0.15)
				)
			)
		)
		(property "Description" "SMD Chip Resistor, 10 kohm, ± 1%, 62.5 mW, 0402 [1005 Metric], Thick Film, General Purpose"
			(at 0 0 270)
			(layer "F.Fab")
			(hide yes)
			(effects
				(font
					(size 1.27 1.27)
					(thickness 0.15)
				)
			)
		)
		(property "MPN" "CR0402-FX-1002GLF"
			(at 0 0 270)
			(unlocked yes)
			(layer "F.Fab")
			(hide yes)
			(effects
				(font
					(size 1 1)
					(thickness 0.15)
				)
			)
		)
		(property "Manufacturer" "Bourns"
			(at 0 0 270)
			(unlocked yes)
			(layer "F.Fab")
			(hide yes)
			(effects
				(font
					(size 1 1)
					(thickness 0.15)
				)
			)
		)
		(property "License" "Apache-2.0"
			(at 0 0 270)
			(unlocked yes)
			(layer "F.Fab")
			(hide yes)
			(effects
				(font
					(size 1 1)
					(thickness 0.15)
				)
			)
		)
		(property "Val" "10k"
			(at 0 0 270)
			(unlocked yes)
			(layer "F.Fab")
			(hide yes)
			(effects
				(font
					(size 1 1)
					(thickness 0.15)
				)
			)
		)
		(property "Tolerance" "1%"
			(at 0 0 270)
			(unlocked yes)
			(layer "F.Fab")
			(hide yes)
			(effects
				(font
					(size 1 1)
					(thickness 0.15)
				)
			)
		)
		(property "Author" "Antmicro"
			(at 0 0 270)
			(unlocked yes)
			(layer "F.Fab")
			(hide yes)
			(effects
				(font
					(size 1 1)
					(thickness 0.15)
				)
			)
		)
		(sheetname "/TB Controller/")
		(sheetfile "tb.kicad_sch")
		(attr smd)
		(fp_rect
			(start -0.925 -0.47)
			(end 0.925 0.47)
			(stroke
				(width 0.05)
				(type default)
			)
			(fill no)
			(layer "F.CrtYd")
		)
		(fp_rect
			(start -0.5 -0.25)
			(end 0.5 0.25)
			(stroke
				(width 0.15)
				(type solid)
			)
			(fill no)
			(layer "F.Fab")
		)
		(fp_text user "License: Apache-2.0"
			(at -0.95 5.169 270)
			(layer "F.Fab")
			(effects
				(font
					(size 0.7 0.7)
					(thickness 0.15)
				)
				(justify left bottom)
			)
		)
		(fp_text user "${REFERENCE}"
			(at -0.95 3.168 270)
			(layer "F.Fab")
			(effects
				(font
					(size 0.7 0.7)
					(thickness 0.15)
				)
				(justify left bottom)
			)
		)
		(fp_text user "Author: Antmicro"
			(at -0.95 4.169 270)
			(layer "F.Fab")
			(effects
				(font
					(size 0.7 0.7)
					(thickness 0.15)
				)
				(justify left bottom)
			)
		)
		(pad "1" smd roundrect
			(at -0.48 0 270)
			(size 0.59 0.64)
			(layers "F.Cu" "F.Mask" "F.Paste")
			(roundrect_rratio 0.25)
			(net 57 "+3V3_TB")
			(pintype "passive")
		)
		(pad "2" smd roundrect
			(at 0.48 0 270)
			(size 0.59 0.64)
			(layers "F.Cu" "F.Mask" "F.Paste")
			(roundrect_rratio 0.25)
			(net 216 "Net-(U4B-PCIE_CLKREQ_N)")
			(pintype "passive")
		)
	)
	(footprint "antmicro-footprints:C_0805_2012Metric"
		(layer "F.Cu")
		(at 149.1 56.8 -90)
		(descr "Capacitor SMD 0805")
		(tags "capacitor SMD 0805")
		(property "Reference" "C319"
			(at 4.6 -0.65 270)
			(layer "F.SilkS")
			(effects
				(font
					(size 0.7 0.7)
					(thickness 0.15)
				)
				(justify left bottom)
			)
		)
		(property "Value" "C_22u_25V_0805"
			(at -2.055717 1.963152 270)
			(layer "F.Fab")
			(effects
				(font
					(size 0.7 0.7)
					(thickness 0.15)
				)
				(justify left bottom)
			)
		)
		(property "Datasheet" "https://product.samsungsem.com/mlcc/CL21A226MAYNNN.do"
			(at 0 0 270)
			(layer "F.Fab")
			(hide yes)
			(effects
				(font
					(size 1.27 1.27)
					(thickness 0.15)
				)
			)
		)
		(property "Description" "SMT Multilayer Ceramic Capacitor, 22uF, +/-20%, 25V, X5R, 0805 [2012 Metric]"
			(at 0 0 270)
			(layer "F.Fab")
			(hide yes)
			(effects
				(font
					(size 1.27 1.27)
					(thickness 0.15)
				)
			)
		)
		(property "MPN" "CL21A226MAYNNNE"
			(at 0 0 270)
			(unlocked yes)
			(layer "F.Fab")
			(hide yes)
			(effects
				(font
					(size 1 1)
					(thickness 0.15)
				)
			)
		)
		(property "Manufacturer" "Samsung Electro-Mechanics"
			(at 0 0 270)
			(unlocked yes)
			(layer "F.Fab")
			(hide yes)
			(effects
				(font
					(size 1 1)
					(thickness 0.15)
				)
			)
		)
		(property "License" "Apache-2.0"
			(at 0 0 270)
			(unlocked yes)
			(layer "F.Fab")
			(hide yes)
			(effects
				(font
					(size 1 1)
					(thickness 0.15)
				)
			)
		)
		(property "Author" "Antmicro"
			(at 0 0 270)
			(unlocked yes)
			(layer "F.Fab")
			(hide yes)
			(effects
				(font
					(size 1 1)
					(thickness 0.15)
				)
			)
		)
		(property "Val" "22u"
			(at 0 0 270)
			(unlocked yes)
			(layer "F.Fab")
			(hide yes)
			(effects
				(font
					(size 1 1)
					(thickness 0.15)
				)
			)
		)
		(property "Voltage" "25V"
			(at 0 0 270)
			(unlocked yes)
			(layer "F.Fab")
			(hide yes)
			(effects
				(font
					(size 1 1)
					(thickness 0.15)
				)
			)
		)
		(property "Dielectric" "X5R"
			(at 0 0 270)
			(unlocked yes)
			(layer "F.Fab")
			(hide yes)
			(effects
				(font
					(size 1 1)
					(thickness 0.15)
				)
			)
		)
		(property "Public" "False"
			(at 0 0 270)
			(unlocked yes)
			(layer "F.Fab")
			(hide yes)
			(effects
				(font
					(size 1 1)
					(thickness 0.15)
				)
			)
		)
		(sheetname "/Power input/")
		(sheetfile "power_input.kicad_sch")
		(attr smd)
		(fp_line
			(start -0.3 0.7)
			(end 0.3 0.7)
			(stroke
				(width 0.15)
				(type solid)
			)
			(layer "F.SilkS")
		)
		(fp_line
			(start -0.3 -0.7)
			(end 0.3 -0.7)
			(stroke
				(width 0.15)
				(type solid)
			)
			(layer "F.SilkS")
		)
		(fp_rect
			(start 1.95 -0.9)
			(end -1.95 0.9)
			(stroke
				(width 0.05)
				(type default)
			)
			(fill no)
			(layer "F.CrtYd")
		)
		(fp_rect
			(start -0.95 -0.675)
			(end 0.95 0.675)
			(stroke
				(width 0.15)
				(type solid)
			)
			(fill no)
			(layer "F.Fab")
		)
		(fp_text user "${REFERENCE}"
			(at -1.9 3.947 270)
			(layer "F.Fab")
			(effects
				(font
					(size 0.7 0.7)
					(thickness 0.15)
				)
				(justify left bottom)
			)
		)
		(fp_text user "License: Apache-2.0"
			(at -1.9 4.947 270)
			(layer "F.Fab")
			(effects
				(font
					(size 0.7 0.7)
					(thickness 0.15)
				)
				(justify left bottom)
			)
		)
		(fp_text user "Author: Antmicro"
			(at -1.9 5.947 270)
			(layer "F.Fab")
			(effects
				(font
					(size 0.7 0.7)
					(thickness 0.15)
				)
				(justify left bottom)
			)
		)
		(pad "1" smd roundrect
			(at -1.1 0 270)
			(size 1.2 1.3)
			(layers "F.Cu" "F.Mask" "F.Paste")
			(roundrect_rratio 0.25)
			(net 23 "GND")
			(pintype "passive")
		)
		(pad "2" smd roundrect
			(at 1.1 0 270)
			(size 1.2 1.3)
			(layers "F.Cu" "F.Mask" "F.Paste")
			(roundrect_rratio 0.25)
			(net 349 "/Power input/5V_OUT")
			(pintype "passive")
		)
	)
	(footprint "antmicro-footprints:R_0402_1005Metric"
		(layer "F.Cu")
		(at 154.305 67.124999 -90)
		(descr "Resistor SMD 0402")
		(tags "resistor SMD 0402")
		(property "Reference" "R151"
			(at -12.324999 -20.295 270)
			(layer "F.SilkS")
			(effects
				(font
					(size 0.7 0.7)
					(thickness 0.15)
				)
			)
		)
		(property "Value" "R_100k_0402"
			(at -1.011843 1.772047 270)
			(layer "F.Fab")
			(effects
				(font
					(size 0.7 0.7)
					(thickness 0.15)
				)
				(justify left bottom)
			)
		)
		(property "Datasheet" "https://www.bourns.com/docs/product-datasheets/cr.pdf"
			(at 0 0 270)
			(layer "F.Fab")
			(hide yes)
			(effects
				(font
					(size 1.27 1.27)
					(thickness 0.15)
				)
			)
		)
		(property "Description" "SMD Chip Resistor, 100 kohm, ± 1%, 62.5 mW, 0402 [1005 Metric], Thick Film, General Purpose"
			(at 0 0 270)
			(layer "F.Fab")
			(hide yes)
			(effects
				(font
					(size 1.27 1.27)
					(thickness 0.15)
				)
			)
		)
		(property "MPN" "CR0402-FX-1003GLF"
			(at 0 0 270)
			(unlocked yes)
			(layer "F.Fab")
			(hide yes)
			(effects
				(font
					(size 1 1)
					(thickness 0.15)
				)
			)
		)
		(property "Manufacturer" "Bourns"
			(at 0 0 270)
			(unlocked yes)
			(layer "F.Fab")
			(hide yes)
			(effects
				(font
					(size 1 1)
					(thickness 0.15)
				)
			)
		)
		(property "License" "Apache-2.0"
			(at 0 0 270)
			(unlocked yes)
			(layer "F.Fab")
			(hide yes)
			(effects
				(font
					(size 1 1)
					(thickness 0.15)
				)
			)
		)
		(property "Author" "Antmicro"
			(at 0 0 270)
			(unlocked yes)
			(layer "F.Fab")
			(hide yes)
			(effects
				(font
					(size 1 1)
					(thickness 0.15)
				)
			)
		)
		(property "Val" "100k"
			(at 0 0 270)
			(unlocked yes)
			(layer "F.Fab")
			(hide yes)
			(effects
				(font
					(size 1 1)
					(thickness 0.15)
				)
			)
		)
		(property "Tolerance" "1%"
			(at 0 0 270)
			(unlocked yes)
			(layer "F.Fab")
			(hide yes)
			(effects
				(font
					(size 1 1)
					(thickness 0.15)
				)
			)
		)
		(sheetname "/X710-AT2 Misc/")
		(sheetfile "x710-at2-mics.kicad_sch")
		(attr smd)
		(fp_rect
			(start -0.925 -0.47)
			(end 0.925 0.47)
			(stroke
				(width 0.05)
				(type default)
			)
			(fill no)
			(layer "F.CrtYd")
		)
		(fp_rect
			(start -0.5 -0.25)
			(end 0.5 0.25)
			(stroke
				(width 0.15)
				(type solid)
			)
			(fill no)
			(layer "F.Fab")
		)
		(fp_text user "${REFERENCE}"
			(at -0.95 3.168 270)
			(layer "F.Fab")
			(effects
				(font
					(size 0.7 0.7)
					(thickness 0.15)
				)
				(justify left bottom)
			)
		)
		(fp_text user "Author: Antmicro"
			(at -0.95 4.169 270)
			(layer "F.Fab")
			(effects
				(font
					(size 0.7 0.7)
					(thickness 0.15)
				)
				(justify left bottom)
			)
		)
		(fp_text user "License: Apache-2.0"
			(at -0.95 5.169 270)
			(layer "F.Fab")
			(effects
				(font
					(size 0.7 0.7)
					(thickness 0.15)
				)
				(justify left bottom)
			)
		)
		(pad "1" smd roundrect
			(at -0.48 0 270)
			(size 0.59 0.64)
			(layers "F.Cu" "F.Mask" "F.Paste")
			(roundrect_rratio 0.25)
			(net 139 "/X710-AT2 Misc/NCSI.RXD_0")
			(pintype "passive")
		)
		(pad "2" smd roundrect
			(at 0.48 0 270)
			(size 0.59 0.64)
			(layers "F.Cu" "F.Mask" "F.Paste")
			(roundrect_rratio 0.25)
			(net 7 "+3V3")
			(pintype "passive")
		)
	)
	(footprint "antmicro-footprints:C_0402_1005Metric"
		(layer "F.Cu")
		(at 143.849999 111.150001 180)
		(descr "Capacitor SMD 0402")
		(tags "capacitor SMD 0402")
		(property "Reference" "C133"
			(at -15.349999 -17.25 180)
			(layer "F.SilkS")
			(effects
				(font
					(size 0.7 0.7)
					(thickness 0.15)
				)
			)
		)
		(property "Value" "C_33p_0402"
			(at -1.022927 2.155213 180)
			(layer "F.Fab")
			(effects
				(font
					(size 0.7 0.7)
					(thickness 0.15)
				)
				(justify left bottom)
			)
		)
		(property "Datasheet" "https://spicat.kyocera-avx.com/product/mlcc/chartview/04025A330FAT2A/"
			(at 0 0 180)
			(layer "F.Fab")
			(hide yes)
			(effects
				(font
					(size 1.27 1.27)
					(thickness 0.15)
				)
			)
		)
		(property "Description" "SMD Multilayer Ceramic Capacitor, 33 pF, 50 V, 0402 [1005 Metric], ± 5%, C0G / NP0, MC"
			(at 0 0 180)
			(layer "F.Fab")
			(hide yes)
			(effects
				(font
					(size 1.27 1.27)
					(thickness 0.15)
				)
			)
		)
		(property "MPN" "04025A330FAT2A"
			(at 0 0 180)
			(unlocked yes)
			(layer "F.Fab")
			(hide yes)
			(effects
				(font
					(size 1 1)
					(thickness 0.15)
				)
			)
		)
		(property "Manufacturer" "KYOCERA AVX"
			(at 0 0 180)
			(unlocked yes)
			(layer "F.Fab")
			(hide yes)
			(effects
				(font
					(size 1 1)
					(thickness 0.15)
				)
			)
		)
		(property "License" "Apache-2.0"
			(at 0 0 180)
			(unlocked yes)
			(layer "F.Fab")
			(hide yes)
			(effects
				(font
					(size 1 1)
					(thickness 0.15)
				)
			)
		)
		(property "Author" "Antmicro"
			(at 0 0 180)
			(unlocked yes)
			(layer "F.Fab")
			(hide yes)
			(effects
				(font
					(size 1 1)
					(thickness 0.15)
				)
			)
		)
		(property "Val" "33p"
			(at 0 0 180)
			(unlocked yes)
			(layer "F.Fab")
			(hide yes)
			(effects
				(font
					(size 1 1)
					(thickness 0.15)
				)
			)
		)
		(property "Voltage" ""
			(at 0 0 180)
			(unlocked yes)
			(layer "F.Fab")
			(hide yes)
			(effects
				(font
					(size 1 1)
					(thickness 0.15)
				)
			)
		)
		(property "Dielectric" ""
			(at 0 0 180)
			(unlocked yes)
			(layer "F.Fab")
			(hide yes)
			(effects
				(font
					(size 1 1)
					(thickness 0.15)
				)
			)
		)
		(sheetname "/X710 DCDC converters/")
		(sheetfile "DCDC_converters_X710.kicad_sch")
		(attr smd dnp)
		(fp_rect
			(start -0.925 -0.47)
			(end 0.925 0.47)
			(stroke
				(width 0.05)
				(type default)
			)
			(fill no)
			(layer "F.CrtYd")
		)
		(fp_line
			(start 0.504 0.248)
			(end -0.494 0.248)
			(stroke
				(width 0.15)
				(type solid)
			)
			(layer "F.Fab")
		)
		(fp_line
			(start 0.504 -0.25)
			(end 0.504 0.248)
			(stroke
				(width 0.15)
				(type solid)
			)
			(layer "F.Fab")
		)
		(fp_line
			(start -0.494 0.248)
			(end -0.494 -0.25)
			(stroke
				(width 0.15)
				(type solid)
			)
			(layer "F.Fab")
		)
		(fp_line
			(start -0.494 -0.25)
			(end 0.504 -0.25)
			(stroke
				(width 0.15)
				(type solid)
			)
			(layer "F.Fab")
		)
		(fp_text user "License: Apache-2.0"
			(at -0.939 5.799 180)
			(layer "F.Fab")
			(effects
				(font
					(size 0.7 0.7)
					(thickness 0.15)
				)
				(justify left bottom)
			)
		)
		(fp_text user "Author: Antmicro"
			(at -0.939 3.399 180)
			(layer "F.Fab")
			(effects
				(font
					(size 0.7 0.7)
					(thickness 0.15)
				)
				(justify left bottom)
			)
		)
		(fp_text user "${REFERENCE}"
			(at -0.939 4.599 180)
			(layer "F.Fab")
			(effects
				(font
					(size 0.7 0.7)
					(thickness 0.15)
				)
				(justify left bottom)
			)
		)
		(pad "1" smd roundrect
			(at -0.48 0 180)
			(size 0.59 0.64)
			(layers "F.Cu" "F.Mask" "F.Paste")
			(roundrect_rratio 0.25)
			(net 342 "/X710 DCDC converters/DVDD_FB")
			(pintype "passive")
		)
		(pad "2" smd roundrect
			(at 0.48 0 180)
			(size 0.59 0.64)
			(layers "F.Cu" "F.Mask" "F.Paste")
			(roundrect_rratio 0.25)
			(net 341 "/X710 DCDC converters/+DVDD_OUT")
			(pintype "passive")
		)
	)
)
